(kicad_pcb
	(version 20260206)
	(generator "pcbnew")
	(generator_version "10.0")
	(general
		(thickness 1.6)
		(legacy_teardrops no)
	)
	(paper "A4")
	(title_block
		(title "03242023_DA0F0TMBIJ0_F0T_Motherboard_J_brd_V01_OCP.brd")
		(comment 1 "Grand Teton / footprints 2912-2913 of 6105")
	)
	(layers
		(0 "F.Cu" signal "TOP")
		(4 "In1.Cu" signal "GND")
		(6 "In2.Cu" signal "IN1")
		(8 "In3.Cu" signal "GND1")
		(10 "In4.Cu" signal "IN2")
		(12 "In5.Cu" signal "GND2")
		(14 "In6.Cu" signal "IN3")
		(16 "In7.Cu" signal "GND3")
		(18 "In8.Cu" signal "VCC")
		(20 "In9.Cu" signal "VCC1")
		(22 "In10.Cu" signal "GND4")
		(24 "In11.Cu" signal "IN4")
		(26 "In12.Cu" signal "GND5")
		(28 "In13.Cu" signal "IN5")
		(30 "In14.Cu" signal "GND6")
		(32 "In15.Cu" signal "IN6")
		(34 "In16.Cu" signal "GND7")
		(2 "B.Cu" signal "BOTTOM")
		(9 "F.Adhes" user "F.Adhesive")
		(11 "B.Adhes" user "B.Adhesive")
		(13 "F.Paste" user "Package Geometry/Pastemask Top")
		(15 "B.Paste" user "Package Geometry/Pastemask Bottom")
		(5 "F.SilkS" user "Ref Des/Silkscreen Top")
		(7 "B.SilkS" user "Ref Des/Silkscreen Bottom")
		(1 "F.Mask" user "Board Geometry/Soldermask Top")
		(3 "B.Mask" user "Board Geometry/Soldermask Bottom")
		(17 "Dwgs.User" user "User.Drawings")
		(19 "Cmts.User" user "User.Comments")
		(21 "Eco1.User" user "User.Eco1")
		(23 "Eco2.User" user "User.Eco2")
		(25 "Edge.Cuts" user "Board Geometry/Outline")
		(27 "Margin" user)
		(31 "F.CrtYd" user "Package Geometry/Place Bound Top")
		(29 "B.CrtYd" user "Package Geometry/Place Bound Bottom")
		(35 "F.Fab" user "Ref Des/Assembly Top")
		(33 "B.Fab" user "Ref Des/Assembly Bottom")
	)
	(footprint ""
		(layer "F.Cu")
		(at 356.51821 -358.848406 -90)
		(property "Reference" "PU14"
			(at -7.271512 3.70967 0)
			(unlocked yes)
			(layer "F.SilkS")
			(effects
				(font
					(size 0.7874 0.5842)
					(thickness 0.1524)
				)
				(justify left)
			)
		)
		(property "Value" ""
			(at 0 0 270)
			(layer "F.Fab")
			(effects
				(font
					(size 1.27 1.27)
				)
			)
		)
		(duplicate_pad_numbers_are_jumpers no)
		(fp_line
			(start -1.400048 3.86969)
			(end -1.400048 3.36169)
			(stroke
				(width 0.1524)
				(type default)
			)
			(layer "F.SilkS")
		)
		(fp_line
			(start 0.599948 3.366008)
			(end 0.599948 4.255008)
			(stroke
				(width 0.1524)
				(type default)
			)
			(layer "F.SilkS")
		)
		(fp_line
			(start -2.999994 2.999994)
			(end -2.999994 2.490978)
			(stroke
				(width 0.1524)
				(type default)
			)
			(layer "F.SilkS")
		)
		(fp_line
			(start -2.518156 2.999994)
			(end -2.999994 2.999994)
			(stroke
				(width 0.1524)
				(type default)
			)
			(layer "F.SilkS")
		)
		(fp_line
			(start 2.999994 2.999994)
			(end 2.47015 2.999994)
			(stroke
				(width 0.1524)
				(type default)
			)
			(layer "F.SilkS")
		)
		(fp_line
			(start 2.999994 2.490978)
			(end 2.999994 2.999994)
			(stroke
				(width 0.1524)
				(type default)
			)
			(layer "F.SilkS")
		)
		(fp_line
			(start 3.3782 2.199894)
			(end 3.8862 2.199894)
			(stroke
				(width 0.1524)
				(type default)
			)
			(layer "F.SilkS")
		)
		(fp_line
			(start -3.3782 1.400048)
			(end -4.2672 1.400048)
			(stroke
				(width 0.1524)
				(type default)
			)
			(layer "F.SilkS")
		)
		(fp_line
			(start 3.3528 0.199898)
			(end 4.2418 0.199898)
			(stroke
				(width 0.1524)
				(type default)
			)
			(layer "F.SilkS")
		)
		(fp_line
			(start -3.3782 -0.599948)
			(end -3.7592 -0.599948)
			(stroke
				(width 0.1524)
				(type default)
			)
			(layer "F.SilkS")
		)
		(fp_line
			(start 3.3528 -1.800098)
			(end 3.8608 -1.800098)
			(stroke
				(width 0.1524)
				(type default)
			)
			(layer "F.SilkS")
		)
		(fp_line
			(start -2.999994 -2.438654)
			(end -2.999994 -2.999994)
			(stroke
				(width 0.1524)
				(type default)
			)
			(layer "F.SilkS")
		)
		(fp_line
			(start -2.999994 -2.999994)
			(end -2.489962 -2.999994)
			(stroke
				(width 0.1524)
				(type default)
			)
			(layer "F.SilkS")
		)
		(fp_line
			(start 2.437384 -2.999994)
			(end 2.999994 -2.999994)
			(stroke
				(width 0.1524)
				(type default)
			)
			(layer "F.SilkS")
		)
		(fp_line
			(start 2.999994 -2.999994)
			(end 2.999994 -2.471166)
			(stroke
				(width 0.1524)
				(type default)
			)
			(layer "F.SilkS")
		)
		(fp_line
			(start -0.999998 -3.3782)
			(end -0.999998 -3.8862)
			(stroke
				(width 0.1524)
				(type default)
			)
			(layer "F.SilkS")
		)
		(fp_line
			(start 0.999998 -4.2545)
			(end 0.999998 -3.3655)
			(stroke
				(width 0.1524)
				(type default)
			)
			(layer "F.SilkS")
		)
		(fp_poly
			(pts
				(xy -3.299206 -2.199894) (xy -3.6449 -2.050034) (xy -3.6449 -2.352294)
			)
			(stroke
				(width 0)
				(type default)
			)
			(fill yes)
			(layer "F.SilkS")
		)
		(fp_line
			(start -1.400048 3.86969)
			(end -1.400048 3.36169)
			(stroke
				(width 0.1)
				(type default)
			)
			(layer "F.Fab")
		)
		(fp_line
			(start 0.599948 3.366008)
			(end 0.599948 4.255008)
			(stroke
				(width 0.1)
				(type default)
			)
			(layer "F.Fab")
		)
		(fp_line
			(start -2.999994 2.999994)
			(end -2.999994 -2.999994)
			(stroke
				(width 0.1)
				(type default)
			)
			(layer "F.Fab")
		)
		(fp_line
			(start 2.999994 2.999994)
			(end -2.999994 2.999994)
			(stroke
				(width 0.1)
				(type default)
			)
			(layer "F.Fab")
		)
		(fp_line
			(start 3.3782 2.199894)
			(end 3.8862 2.199894)
			(stroke
				(width 0.1)
				(type default)
			)
			(layer "F.Fab")
		)
		(fp_line
			(start -3.3782 1.400048)
			(end -4.2672 1.400048)
			(stroke
				(width 0.1)
				(type default)
			)
			(layer "F.Fab")
		)
		(fp_line
			(start 3.3528 0.199898)
			(end 4.2418 0.199898)
			(stroke
				(width 0.1)
				(type default)
			)
			(layer "F.Fab")
		)
		(fp_line
			(start -3.3782 -0.599948)
			(end -3.7592 -0.599948)
			(stroke
				(width 0.1)
				(type default)
			)
			(layer "F.Fab")
		)
		(fp_line
			(start 3.3528 -1.800098)
			(end 3.8608 -1.800098)
			(stroke
				(width 0.1)
				(type default)
			)
			(layer "F.Fab")
		)
		(fp_line
			(start -2.999994 -2.999994)
			(end 2.999994 -2.999994)
			(stroke
				(width 0.1)
				(type default)
			)
			(layer "F.Fab")
		)
		(fp_line
			(start 2.999994 -2.999994)
			(end 2.999994 2.999994)
			(stroke
				(width 0.1)
				(type default)
			)
			(layer "F.Fab")
		)
		(fp_line
			(start -0.999998 -3.3782)
			(end -0.999998 -3.8862)
			(stroke
				(width 0.1)
				(type default)
			)
			(layer "F.Fab")
		)
		(fp_line
			(start 0.999998 -4.2545)
			(end 0.999998 -3.3655)
			(stroke
				(width 0.1)
				(type default)
			)
			(layer "F.Fab")
		)
		(fp_poly
			(pts
				(xy -3.6449 -2.352294) (xy -3.6449 -2.050034) (xy -3.299206 -2.199894)
			)
			(stroke
				(width 0)
				(type default)
			)
			(fill yes)
			(layer "F.Fab")
		)
		(fp_text user "24"
			(at 4.862068 9.55675 0)
			(unlocked yes)
			(layer "F.SilkS")
			(effects
				(font
					(size 0.7874 0.5842)
					(thickness 0.1524)
				)
				(justify left)
			)
		)
		(fp_text user "13"
			(at -3.420872 4.73075 0)
			(unlocked yes)
			(layer "F.SilkS")
			(effects
				(font
					(size 0.7874 0.5842)
					(thickness 0.1524)
				)
				(justify left)
			)
		)
		(fp_text user "12"
			(at -5.600192 3.84937 0)
			(unlocked yes)
			(layer "F.SilkS")
			(effects
				(font
					(size 0.7874 0.5842)
					(thickness 0.1524)
				)
				(justify left)
			)
		)
		(fp_text user "25"
			(at 3.889248 1.95961 0)
			(unlocked yes)
			(layer "F.SilkS")
			(effects
				(font
					(size 0.7874 0.5842)
					(thickness 0.1524)
				)
				(justify left)
			)
		)
		(fp_text user "48"
			(at -4.271772 -1.27889 0)
			(unlocked yes)
			(layer "F.SilkS")
			(effects
				(font
					(size 0.7874 0.5842)
					(thickness 0.1524)
				)
				(justify left)
			)
		)
		(fp_text user "36"
			(at 4.679188 -2.01041 0)
			(unlocked yes)
			(layer "F.SilkS")
			(effects
				(font
					(size 0.7874 0.5842)
					(thickness 0.1524)
				)
				(justify left)
			)
		)
		(fp_text user "48"
			(at -6.788912 -2.77495 0)
			(unlocked yes)
			(layer "F.SilkS")
			(effects
				(font
					(size 0.7874 0.5842)
					(thickness 0.1524)
				)
				(justify left)
			)
		)
		(fp_text user "37"
			(at 2.708148 -3.30581 0)
			(unlocked yes)
			(layer "F.SilkS")
			(effects
				(font
					(size 0.7874 0.5842)
					(thickness 0.1524)
				)
				(justify left)
			)
		)
		(fp_text user "13"
			(at -3.5814 3.794252 270)
			(unlocked yes)
			(layer "F.Fab")
			(effects
				(font
					(size 0.7874 0.5842)
					(thickness 0.1524)
				)
				(justify left)
			)
		)
		(fp_text user "24"
			(at 2.1844 3.768852 270)
			(unlocked yes)
			(layer "F.Fab")
			(effects
				(font
					(size 0.7874 0.5842)
					(thickness 0.1524)
				)
				(justify left)
			)
		)
		(fp_text user "25"
			(at 3.2004 2.829052 270)
			(unlocked yes)
			(layer "F.Fab")
			(effects
				(font
					(size 0.7874 0.5842)
					(thickness 0.1524)
				)
				(justify left)
			)
		)
		(fp_text user "12"
			(at -4.6228 2.752852 270)
			(unlocked yes)
			(layer "F.Fab")
			(effects
				(font
					(size 0.7874 0.5842)
					(thickness 0.1524)
				)
				(justify left)
			)
		)
		(fp_text user "36"
			(at 3.2258 -2.733548 270)
			(unlocked yes)
			(layer "F.Fab")
			(effects
				(font
					(size 0.7874 0.5842)
					(thickness 0.1524)
				)
				(justify left)
			)
		)
		(fp_text user "37"
			(at 2.2352 -3.724148 270)
			(unlocked yes)
			(layer "F.Fab")
			(effects
				(font
					(size 0.7874 0.5842)
					(thickness 0.1524)
				)
				(justify left)
			)
		)
		(fp_text user "48"
			(at -3.509264 -3.740658 270)
			(unlocked yes)
			(layer "F.Fab")
			(effects
				(font
					(size 0.7874 0.5842)
					(thickness 0.1524)
				)
				(justify left)
			)
		)
		(pad "1" smd rect
			(at -2.875026 -2.199894)
			(size 0.1778 0.6604)
			(layers "F.Cu" "F.Mask" "F.Paste")
			(net "PVCCFA_EHV_FIVRA_CPU0_PWM1")
		)
		(pad "2" smd rect
			(at -2.875026 -1.800098)
			(size 0.1778 0.6604)
			(layers "F.Cu" "F.Mask" "F.Paste")
			(net "PVCCFA_EHV_FIVRA_CPU0_PWM2")
		)
		(pad "3" smd rect
			(at -2.875026 -1.400048)
			(size 0.1778 0.6604)
			(layers "F.Cu" "F.Mask" "F.Paste")
			(net "PVCCFA_EHV_FIVRA_CPU0_PWM3")
		)
		(pad "4" smd rect
			(at -2.875026 -0.999998)
			(size 0.1778 0.6604)
			(layers "F.Cu" "F.Mask" "F.Paste")
			(net "PVCCFA_EHV_FIVRA_CPU0_PWM4")
		)
		(pad "5" smd rect
			(at -2.875026 -0.599948)
			(size 0.1778 0.6604)
			(layers "F.Cu" "F.Mask" "F.Paste")
			(net "PVCCIN_CPU0_PWM8")
		)
		(pad "6" smd rect
			(at -2.875026 -0.199898)
			(size 0.1778 0.6604)
			(layers "F.Cu" "F.Mask" "F.Paste")
			(net "PVCCIN_CPU0_PWM7")
		)
		(pad "7" smd rect
			(at -2.875026 0.199898)
			(size 0.1778 0.6604)
			(layers "F.Cu" "F.Mask" "F.Paste")
			(net "PVCCIN_CPU0_PWM6")
		)
		(pad "8" smd rect
			(at -2.875026 0.599948)
			(size 0.1778 0.6604)
			(layers "F.Cu" "F.Mask" "F.Paste")
			(net "PVCCIN_CPU0_PWM5")
		)
		(pad "9" smd rect
			(at -2.875026 0.999998)
			(size 0.1778 0.6604)
			(layers "F.Cu" "F.Mask" "F.Paste")
			(net "PVCCIN_CPU0_PWM4")
		)
		(pad "10" smd rect
			(at -2.875026 1.400048)
			(size 0.1778 0.6604)
			(layers "F.Cu" "F.Mask" "F.Paste")
			(net "PVCCIN_CPU0_PWM3")
		)
		(pad "11" smd rect
			(at -2.875026 1.800098)
			(size 0.1778 0.6604)
			(layers "F.Cu" "F.Mask" "F.Paste")
			(net "PVCCIN_CPU0_PWM2")
		)
		(pad "12" smd rect
			(at -2.875026 2.199894)
			(size 0.1778 0.6604)
			(layers "F.Cu" "F.Mask" "F.Paste")
			(net "PVCCIN_CPU0_PWM1")
		)
		(pad "13" smd rect
			(at -2.199894 2.875026 270)
			(size 0.1778 0.6604)
			(layers "F.Cu" "F.Mask" "F.Paste")
			(net "SMB_DIO_PVCCIN_CPU0")
		)
		(pad "14" smd rect
			(at -1.800098 2.875026 270)
			(size 0.1778 0.6604)
			(layers "F.Cu" "F.Mask" "F.Paste")
			(net "SMB_CLK_PVCCIN_CPU0")
		)
		(pad "15" smd rect
			(at -1.400048 2.875026 270)
			(size 0.1778 0.6604)
			(layers "F.Cu" "F.Mask" "F.Paste")
			(net "NC_PVCCIN_CPU0_SMB_ALERT")
		)
		(pad "16" smd rect
			(at -0.999998 2.875026 270)
			(size 0.1778 0.6604)
			(layers "F.Cu" "F.Mask" "F.Paste")
			(net "PWRGD_PVCCIN_CPU0_R")
		)
		(pad "17" smd rect
			(at -0.599948 2.875026 270)
			(size 0.1778 0.6604)
			(layers "F.Cu" "F.Mask" "F.Paste")
			(net "PVCCIN_CPU0_EN_R")
		)
		(pad "18" smd rect
			(at -0.199898 2.875026 270)
			(size 0.1778 0.6604)
			(layers "F.Cu" "F.Mask" "F.Paste")
			(net "IRQ_PVCCIN_CPU0_VRHOT_N")
		)
		(pad "19" smd rect
			(at 0.199898 2.875026 270)
			(size 0.1778 0.6604)
			(layers "F.Cu" "F.Mask" "F.Paste")
			(net "PVCCIN_CPU0_PIN_ALERT")
		)
		(pad "20" smd rect
			(at 0.599948 2.875026 270)
			(size 0.1778 0.6604)
			(layers "F.Cu" "F.Mask" "F.Paste")
			(net "PWRGD_PVCCFA_EHV_FIVRA_CPU0_R")
		)
		(pad "21" smd rect
			(at 0.999998 2.875026 270)
			(size 0.1778 0.6604)
			(layers "F.Cu" "F.Mask" "F.Paste")
			(net "SVID_CLK_PVCCIN_CPU0_R")
		)
		(pad "22" smd rect
			(at 1.400048 2.875026 270)
			(size 0.1778 0.6604)
			(layers "F.Cu" "F.Mask" "F.Paste")
			(net "SVID_DIO_PVCCIN_CPU0_R")
		)
		(pad "23" smd rect
			(at 1.800098 2.875026 270)
			(size 0.1778 0.6604)
			(layers "F.Cu" "F.Mask" "F.Paste")
			(net "SVID_ALERT_PVCCIN_CPU0_R")
		)
		(pad "24" smd rect
			(at 2.199894 2.875026 270)
			(size 0.1778 0.6604)
			(layers "F.Cu" "F.Mask" "F.Paste")
			(net "PVCCFA_EHV_FIVRA_CPU0_EN_R")
		)
		(pad "25" smd rect
			(at 2.875026 2.199894)
			(size 0.1778 0.6604)
			(layers "F.Cu" "F.Mask" "F.Paste")
			(net "SH_PVCCIN_CPU0_R")
		)
		(pad "26" smd rect
			(at 2.875026 1.800098)
			(size 0.1778 0.6604)
			(layers "F.Cu" "F.Mask" "F.Paste")
			(net "VSENSE_PVCCIN_CPU0_DN")
		)
		(pad "27" smd rect
			(at 2.875026 1.400048)
			(size 0.1778 0.6604)
			(layers "F.Cu" "F.Mask" "F.Paste")
			(net "PVCCIN_CPU0_IMON1")
		)
		(pad "28" smd rect
			(at 2.875026 0.999998)
			(size 0.1778 0.6604)
			(layers "F.Cu" "F.Mask" "F.Paste")
			(net "PVCCIN_CPU0_IMON2")
		)
		(pad "29" smd rect
			(at 2.875026 0.599948)
			(size 0.1778 0.6604)
			(layers "F.Cu" "F.Mask" "F.Paste")
			(net "PVCCIN_CPU0_IMON3")
		)
		(pad "30" smd rect
			(at 2.875026 0.199898)
			(size 0.1778 0.6604)
			(layers "F.Cu" "F.Mask" "F.Paste")
			(net "PVCCIN_CPU0_IMON4")
		)
		(pad "31" smd rect
			(at 2.875026 -0.199898)
			(size 0.1778 0.6604)
			(layers "F.Cu" "F.Mask" "F.Paste")
			(net "PVCCIN_CPU0_IMON5")
		)
		(pad "32" smd rect
			(at 2.875026 -0.599948)
			(size 0.1778 0.6604)
			(layers "F.Cu" "F.Mask" "F.Paste")
			(net "PVCCIN_CPU0_IMON6")
		)
		(pad "33" smd rect
			(at 2.875026 -0.999998)
			(size 0.1778 0.6604)
			(layers "F.Cu" "F.Mask" "F.Paste")
			(net "PVCCIN_CPU0_IMON7")
		)
		(pad "34" smd rect
			(at 2.875026 -1.400048)
			(size 0.1778 0.6604)
			(layers "F.Cu" "F.Mask" "F.Paste")
			(net "PVCCIN_CPU0_IMON8")
		)
		(pad "35" smd rect
			(at 2.875026 -1.800098)
			(size 0.1778 0.6604)
			(layers "F.Cu" "F.Mask" "F.Paste")
			(net "PVCCFA_EHV_FIVRA_CPU0_IMON4")
		)
		(pad "36" smd rect
			(at 2.875026 -2.199894)
			(size 0.1778 0.6604)
			(layers "F.Cu" "F.Mask" "F.Paste")
			(net "PVCCFA_EHV_FIVRA_CPU0_IMON3")
		)
		(pad "37" smd rect
			(at 2.199894 -2.875026 270)
			(size 0.1778 0.6604)
			(layers "F.Cu" "F.Mask" "F.Paste")
			(net "PVCCFA_EHV_FIVRA_CPU0_IMON2")
		)
		(pad "38" smd rect
			(at 1.800098 -2.875026 270)
			(size 0.1778 0.6604)
			(layers "F.Cu" "F.Mask" "F.Paste")
			(net "PVCCFA_EHV_FIVRA_CPU0_IMON1")
		)
		(pad "39" smd rect
			(at 1.400048 -2.875026 270)
			(size 0.1778 0.6604)
			(layers "F.Cu" "F.Mask" "F.Paste")
			(net "VSENSE_PVCCFA_EHV_FIVRA_CPU0_DN")
		)
		(pad "40" smd rect
			(at 0.999998 -2.875026 270)
			(size 0.1778 0.6604)
			(layers "F.Cu" "F.Mask" "F.Paste")
			(net "SH_PVCCFA_EHV_FIVRA_CPU0_R")
		)
		(pad "41" smd rect
			(at 0.599948 -2.875026 270)
			(size 0.1778 0.6604)
			(layers "F.Cu" "F.Mask" "F.Paste")
			(net "PVCCIN_CPU0_VR_FAULT")
		)
		(pad "42" smd rect
			(at 0.199898 -2.875026 270)
			(size 0.1778 0.6604)
			(layers "F.Cu" "F.Mask" "F.Paste")
			(net "PVCCIN_CPU0_ADDR")
		)
		(pad "43" smd rect
			(at -0.199898 -2.875026 270)
			(size 0.1778 0.6604)
			(layers "F.Cu" "F.Mask" "F.Paste")
			(net "PVCCIN_CPU0_ATSEN")
		)
		(pad "44" smd rect
			(at -0.599948 -2.875026 270)
			(size 0.1778 0.6604)
			(layers "F.Cu" "F.Mask" "F.Paste")
			(net "PVCCFA_EHV_FIVRA_CPU0_BTSEN")
		)
		(pad "45" smd rect
			(at -0.999998 -2.875026 270)
			(size 0.1778 0.6604)
			(layers "F.Cu" "F.Mask" "F.Paste")
			(net "PVCCIN_CPU0_CSPIN")
		)
		(pad "46" smd rect
			(at -1.400048 -2.875026 270)
			(size 0.1778 0.6604)
			(layers "F.Cu" "F.Mask" "F.Paste")
			(net "PVCCIN_CPU0_VIN_CSNIN")
		)
		(pad "47" smd rect
			(at -1.800098 -2.875026 270)
			(size 0.1778 0.6604)
			(layers "F.Cu" "F.Mask" "F.Paste")
			(net "PVCCIN_CPU0_VCC")
		)
		(pad "48" smd rect
			(at -2.199894 -2.875026 270)
			(size 0.1778 0.6604)
			(layers "F.Cu" "F.Mask" "F.Paste")
			(net "PVCCIN_CPU0_VREF")
		)
		(pad "TH" smd rect
			(at 0 0 270)
			(size 4.4196 4.4196)
			(layers "F.Cu" "F.Mask" "F.Paste")
			(net "GND")
		)
		(zone
			(layer "F.Cu")
			(hatch none 0.5)
			(connect_pads
				(clearance 0)
			)
			(min_thickness 0.25)
			(keepout
				(tracks not_allowed)
				(vias allowed)
				(pads allowed)
				(copperpour not_allowed)
				(footprints allowed)
			)
			(placement
				(enabled no)
				(sheetname "")
			)
			(fill
				(thermal_gap 0.5)
				(thermal_bridge_width 0.5)
				(island_removal_mode 0)
			)
			(polygon
				(pts
					(xy 354.30841 -361.337606) (xy 354.30841 -361.236006) (xy 354.30841 -361.134406) (xy 354.23221 -361.134406)
					(xy 354.23221 -356.562406) (xy 358.80421 -356.562406) (xy 358.80421 -361.134406) (xy 354.33381 -361.134406)
					(xy 354.33381 -361.236006) (xy 354.33381 -361.337606) (xy 358.98201 -361.337606) (xy 359.00741 -361.337606)
					(xy 359.00741 -356.359206) (xy 358.98201 -356.359206) (xy 354.02901 -356.359206) (xy 354.02901 -361.337606)
				)
			)
		)
	)
	(footprint ""
		(layer "F.Cu")
		(at 346.840048 -402.371052 -90)
		(property "Reference" "C1550"
			(at 0 0 270)
			(layer "F.SilkS")
			(hide yes)
			(effects
				(font
					(size 1.27 1.27)
				)
			)
		)
		(property "Value" ""
			(at 0 0 270)
			(layer "F.Fab")
			(effects
				(font
					(size 1.27 1.27)
				)
			)
		)
		(duplicate_pad_numbers_are_jumpers no)
		(fp_line
			(start -0.299974 0.150114)
			(end -0.299974 -0.150114)
			(stroke
				(width 0.1)
				(type default)
			)
			(layer "F.Fab")
		)
		(fp_line
			(start 0.299974 0.150114)
			(end -0.299974 0.150114)
			(stroke
				(width 0.1)
				(type default)
			)
			(layer "F.Fab")
		)
		(fp_line
			(start -0.299974 -0.150114)
			(end 0.299974 -0.150114)
			(stroke
				(width 0.1)
				(type default)
			)
			(layer "F.Fab")
		)
		(fp_line
			(start 0.299974 -0.150114)
			(end 0.299974 0.150114)
			(stroke
				(width 0.1)
				(type default)
			)
			(layer "F.Fab")
		)
		(pad "1" smd rect
			(at -0.2667 0 270)
			(size 0.3048 0.381)
			(layers "F.Cu" "F.Mask" "F.Paste")
			(net "P5E_CPU0_PE4_TX_C_DN<14>")
		)
		(pad "2" smd rect
			(at 0.2667 0 270)
			(size 0.3048 0.381)
			(layers "F.Cu" "F.Mask" "F.Paste")
			(net "P5E_CPU0_PE4_TX_DN<14>")
		)
	)
)
